# T6G (Grand Teton) — schematic netlist excerpt (pin names and nets, part order shuffled) for the footprints in the layout excerpt that follows; sources: Cadence DE-HDL packaged netlist, KiCad conversion of 04192023_DAF0TMB3IC0_F0TG_MB_C_brd_V02_OCP.brd

R137  Q_RES  0 5% CHIP  pkg 0402LF  page 82 : A = PVDDCR_CPU1_P0_OCP_N ; B = FM_PVDDCR_CPU1_P0_OCP_N
R220  Q_RES  33 5% CHIP  pkg 0402LF  page 82 : A = FM_CPU0_SA0 ; B = CPU0_SA0

(kicad_pcb
	(version 20260206)
	(generator "pcbnew")
	(generator_version "10.0")
	(general
		(thickness 1.6)
		(legacy_teardrops no)
	)
	(paper "A4")
	(title_block
		(title "04192023_DAF0TMB3IC0_F0TG_MB_C_brd_V02_OCP.brd")
		(comment 1 "Grand Teton / footprints 6596-6597 of 8354")
	)
	(layers
		(0 "F.Cu" signal "TOP")
		(4 "In1.Cu" signal "GND")
		(6 "In2.Cu" signal "IN1")
		(8 "In3.Cu" signal "GND1")
		(10 "In4.Cu" signal "IN2")
		(12 "In5.Cu" signal "GND2")
		(14 "In6.Cu" signal "IN3")
		(16 "In7.Cu" signal "GND3")
		(18 "In8.Cu" signal "VCC")
		(20 "In9.Cu" signal "VCC1")
		(22 "In10.Cu" signal "GND4")
		(24 "In11.Cu" signal "IN4")
		(26 "In12.Cu" signal "GND5")
		(28 "In13.Cu" signal "IN5")
		(30 "In14.Cu" signal "GND6")
		(32 "In15.Cu" signal "IN6")
		(34 "In16.Cu" signal "GND7")
		(2 "B.Cu" signal "BOTTOM")
		(9 "F.Adhes" user "F.Adhesive")
		(11 "B.Adhes" user "B.Adhesive")
		(13 "F.Paste" user "Package Geometry/Pastemask Top")
		(15 "B.Paste" user "Package Geometry/Pastemask Bottom")
		(5 "F.SilkS" user "Ref Des/Silkscreen Top")
		(7 "B.SilkS" user "Ref Des/Silkscreen Bottom")
		(1 "F.Mask" user "Board Geometry/Soldermask Top")
		(3 "B.Mask" user "Board Geometry/Soldermask Bottom")
		(17 "Dwgs.User" user "User.Drawings")
		(19 "Cmts.User" user "User.Comments")
		(21 "Eco1.User" user "User.Eco1")
		(23 "Eco2.User" user "User.Eco2")
		(25 "Edge.Cuts" user "Board Geometry/Outline")
		(27 "Margin" user)
		(31 "F.CrtYd" user "Package Geometry/Place Bound Top")
		(29 "B.CrtYd" user "Package Geometry/Place Bound Bottom")
		(35 "F.Fab" user "Ref Des/Assembly Top")
		(33 "B.Fab" user "Ref Des/Assembly Bottom")
	)
	(footprint ""
		(layer "B.Cu")
		(at 179.705 -100.294948 -90)
		(property "Reference" "R137"
			(at 0 0 90)
			(layer "B.SilkS")
			(hide yes)
			(effects
				(font
					(size 1.27 1.27)
				)
				(justify mirror)
			)
		)
		(property "Value" ""
			(at 0 0 90)
			(layer "B.Fab")
			(effects
				(font
					(size 1.27 1.27)
				)
				(justify mirror)
			)
		)
		(duplicate_pad_numbers_are_jumpers no)
		(fp_line
			(start -0.7874 0.4064)
			(end 0.7874 0.4064)
			(stroke
				(width 0.1524)
				(type default)
			)
			(layer "B.SilkS")
		)
		(fp_line
			(start 0.7874 0.4064)
			(end 0.7874 -0.4064)
			(stroke
				(width 0.1524)
				(type default)
			)
			(layer "B.SilkS")
		)
		(fp_line
			(start -0.7874 -0.4064)
			(end -0.7874 0.4064)
			(stroke
				(width 0.1524)
				(type default)
			)
			(layer "B.SilkS")
		)
		(fp_line
			(start 0.7874 -0.4064)
			(end -0.7874 -0.4064)
			(stroke
				(width 0.1524)
				(type default)
			)
			(layer "B.SilkS")
		)
		(fp_line
			(start -0.67945 0.3048)
			(end -0.120396 0.3048)
			(stroke
				(width 0.1)
				(type default)
			)
			(layer "B.Fab")
		)
		(fp_line
			(start -0.120396 0.3048)
			(end -0.120396 0.2794)
			(stroke
				(width 0.1)
				(type default)
			)
			(layer "B.Fab")
		)
		(fp_line
			(start 0.12065 0.3048)
			(end 0.67945 0.3048)
			(stroke
				(width 0.1)
				(type default)
			)
			(layer "B.Fab")
		)
		(fp_line
			(start 0.67945 0.3048)
			(end 0.67945 -0.305054)
			(stroke
				(width 0.1)
				(type default)
			)
			(layer "B.Fab")
		)
		(fp_line
			(start -0.120396 0.2794)
			(end 0.12065 0.2794)
			(stroke
				(width 0.1)
				(type default)
			)
			(layer "B.Fab")
		)
		(fp_line
			(start 0.12065 0.2794)
			(end 0.12065 0.3048)
			(stroke
				(width 0.1)
				(type default)
			)
			(layer "B.Fab")
		)
		(fp_line
			(start -0.12065 -0.2794)
			(end -0.12065 -0.3048)
			(stroke
				(width 0.1)
				(type default)
			)
			(layer "B.Fab")
		)
		(fp_line
			(start 0.12065 -0.2794)
			(end -0.12065 -0.2794)
			(stroke
				(width 0.1)
				(type default)
			)
			(layer "B.Fab")
		)
		(fp_line
			(start -0.67945 -0.3048)
			(end -0.67945 0.3048)
			(stroke
				(width 0.1)
				(type default)
			)
			(layer "B.Fab")
		)
		(fp_line
			(start -0.12065 -0.3048)
			(end -0.67945 -0.3048)
			(stroke
				(width 0.1)
				(type default)
			)
			(layer "B.Fab")
		)
		(fp_line
			(start 0.12065 -0.305054)
			(end 0.12065 -0.2794)
			(stroke
				(width 0.1)
				(type default)
			)
			(layer "B.Fab")
		)
		(fp_line
			(start 0.67945 -0.305054)
			(end 0.12065 -0.305054)
			(stroke
				(width 0.1)
				(type default)
			)
			(layer "B.Fab")
		)
		(pad "1" smd circle
			(at 0.40005 0 90)
			(size 0 0)
			(layers "B.Cu" "B.Mask" "B.Paste")
			(net "PVDDCR_CPU1_P0_OCP_N")
		)
		(pad "2" smd circle
			(at -0.40005 0 90)
			(size 0 0)
			(layers "B.Cu" "B.Mask" "B.Paste")
			(net "FM_PVDDCR_CPU1_P0_OCP_N")
		)
	)
	(footprint ""
		(layer "B.Cu")
		(at 192.913 -100.294948 90)
		(property "Reference" "R220"
			(at 0 0 90)
			(layer "B.SilkS")
			(hide yes)
			(effects
				(font
					(size 1.27 1.27)
				)
				(justify mirror)
			)
		)
		(property "Value" ""
			(at 0 0 90)
			(layer "B.Fab")
			(effects
				(font
					(size 1.27 1.27)
				)
				(justify mirror)
			)
		)
		(duplicate_pad_numbers_are_jumpers no)
		(fp_line
			(start 0.7874 -0.4064)
			(end -0.7874 -0.4064)
			(stroke
				(width 0.1524)
				(type default)
			)
			(layer "B.SilkS")
		)
		(fp_line
			(start -0.7874 -0.4064)
			(end -0.7874 0.4064)
			(stroke
				(width 0.1524)
				(type default)
			)
			(layer "B.SilkS")
		)
		(fp_line
			(start 0.7874 0.4064)
			(end 0.7874 -0.4064)
			(stroke
				(width 0.1524)
				(type default)
			)
			(layer "B.SilkS")
		)
		(fp_line
			(start -0.7874 0.4064)
			(end 0.7874 0.4064)
			(stroke
				(width 0.1524)
				(type default)
			)
			(layer "B.SilkS")
		)
		(fp_line
			(start 0.67945 -0.305054)
			(end 0.12065 -0.305054)
			(stroke
				(width 0.1)
				(type default)
			)
			(layer "B.Fab")
		)
		(fp_line
			(start 0.12065 -0.305054)
			(end 0.12065 -0.2794)
			(stroke
				(width 0.1)
				(type default)
			)
			(layer "B.Fab")
		)
		(fp_line
			(start -0.12065 -0.3048)
			(end -0.67945 -0.3048)
			(stroke
				(width 0.1)
				(type default)
			)
			(layer "B.Fab")
		)
		(fp_line
			(start -0.67945 -0.3048)
			(end -0.67945 0.3048)
			(stroke
				(width 0.1)
				(type default)
			)
			(layer "B.Fab")
		)
		(fp_line
			(start 0.12065 -0.2794)
			(end -0.12065 -0.2794)
			(stroke
				(width 0.1)
				(type default)
			)
			(layer "B.Fab")
		)
		(fp_line
			(start -0.12065 -0.2794)
			(end -0.12065 -0.3048)
			(stroke
				(width 0.1)
				(type default)
			)
			(layer "B.Fab")
		)
		(fp_line
			(start 0.12065 0.2794)
			(end 0.12065 0.3048)
			(stroke
				(width 0.1)
				(type default)
			)
			(layer "B.Fab")
		)
		(fp_line
			(start -0.120396 0.2794)
			(end 0.12065 0.2794)
			(stroke
				(width 0.1)
				(type default)
			)
			(layer "B.Fab")
		)
		(fp_line
			(start 0.67945 0.3048)
			(end 0.67945 -0.305054)
			(stroke
				(width 0.1)
				(type default)
			)
			(layer "B.Fab")
		)
		(fp_line
			(start 0.12065 0.3048)
			(end 0.67945 0.3048)
			(stroke
				(width 0.1)
				(type default)
			)
			(layer "B.Fab")
		)
		(fp_line
			(start -0.120396 0.3048)
			(end -0.120396 0.2794)
			(stroke
				(width 0.1)
				(type default)
			)
			(layer "B.Fab")
		)
		(fp_line
			(start -0.67945 0.3048)
			(end -0.120396 0.3048)
			(stroke
				(width 0.1)
				(type default)
			)
			(layer "B.Fab")
		)
		(pad "1" smd circle
			(at 0.40005 0 270)
			(size 0 0)
			(layers "B.Cu" "B.Mask" "B.Paste")
			(net "FM_CPU0_SA0")
		)
		(pad "2" smd circle
			(at -0.40005 0 270)
			(size 0 0)
			(layers "B.Cu" "B.Mask" "B.Paste")
			(net "CPU0_SA0")
		)
	)
)
